(kicad_pcb
	(version 20241229)
	(generator "pcbnew")
	(generator_version "9.0")
	(general
		(thickness 1.61)
		(legacy_teardrops no)
	)
	(paper "A3")
	(title_block
		(title "SO-DIMM DDR5 Tester")
		(date "2025-11-26")
		(rev "1.3.0")
		(comment 9 "footprints 235-241 of 627")
	)
	(layers
		(0 "F.Cu" signal)
		(4 "In1.Cu" power)
		(6 "In2.Cu" mixed)
		(8 "In3.Cu" power)
		(10 "In4.Cu" mixed)
		(12 "In5.Cu" power)
		(14 "In6.Cu" mixed)
		(16 "In7.Cu" power)
		(18 "In8.Cu" power)
		(20 "In9.Cu" mixed)
		(22 "In10.Cu" power)
		(2 "B.Cu" signal)
		(9 "F.Adhes" user "F.Adhesive")
		(11 "B.Adhes" user "B.Adhesive")
		(13 "F.Paste" user)
		(15 "B.Paste" user)
		(5 "F.SilkS" user "F.Silkscreen")
		(7 "B.SilkS" user "B.Silkscreen")
		(1 "F.Mask" user)
		(3 "B.Mask" user)
		(17 "Dwgs.User" user "User.Drawings")
		(19 "Cmts.User" user "User.Comments")
		(21 "Eco1.User" user "User.Eco1")
		(23 "Eco2.User" user "User.Eco2")
		(25 "Edge.Cuts" user)
		(27 "Margin" user)
		(31 "F.CrtYd" user "F.Courtyard")
		(29 "B.CrtYd" user "B.Courtyard")
		(35 "F.Fab" user)
		(33 "B.Fab" user)
	)
	(footprint "antmicro-footprints:FB_0603_1608Metric"
		(layer "F.Cu")
		(at 86.577001 187.4505)
		(property "Reference" "FB3"
			(at 0 -0.8 0)
			(layer "F.SilkS")
			(hide yes)
			(effects
				(font
					(size 0.7 0.7)
					(thickness 0.15)
				)
				(justify left bottom)
			)
		)
		(property "Value" "FB_120Z_2A_Murata-BLM18PG_0603"
			(at 0 1.5 0)
			(layer "F.Fab")
			(effects
				(font
					(size 0.7 0.7)
					(thickness 0.15)
				)
				(justify left bottom)
			)
		)
		(property "Datasheet" "https://www.murata.com/en-us/products/productdata/8796738650142/ENFA0003.pdf"
			(at 0 0 0)
			(layer "F.Fab")
			(hide yes)
			(effects
				(font
					(size 1.27 1.27)
					(thickness 0.15)
				)
			)
		)
		(property "Author" "Antmicro"
			(at 0 0 0)
			(layer "F.Fab")
			(hide yes)
			(effects
				(font
					(size 1 1)
					(thickness 0.15)
				)
			)
		)
		(property "License" "Apache-2.0"
			(at 0 0 0)
			(layer "F.Fab")
			(hide yes)
			(effects
				(font
					(size 1 1)
					(thickness 0.15)
				)
			)
		)
		(property "MPN" "BLM18PG121SN1D"
			(at 0 0 0)
			(layer "F.Fab")
			(hide yes)
			(effects
				(font
					(size 1 1)
					(thickness 0.15)
				)
			)
		)
		(property "Manufacturer" "Murata"
			(at 0 0 0)
			(layer "F.Fab")
			(hide yes)
			(effects
				(font
					(size 1 1)
					(thickness 0.15)
				)
			)
		)
		(property "Val" "120Z/2A"
			(at 0 0 0)
			(layer "F.Fab")
			(hide yes)
			(effects
				(font
					(size 1 1)
					(thickness 0.15)
				)
			)
		)
		(sheetname "/HDMI + SD Card/")
		(sheetfile "hdmi-sd-card.kicad_sch")
		(attr smd)
		(fp_line
			(start -0.196 -0.408)
			(end 0.193 -0.408)
			(stroke
				(width 0.15)
				(type solid)
			)
			(layer "F.SilkS")
		)
		(fp_line
			(start -0.196 0.406)
			(end 0.193 0.406)
			(stroke
				(width 0.15)
				(type solid)
			)
			(layer "F.SilkS")
		)
		(fp_rect
			(start -1.3 -0.6)
			(end 1.3 0.6)
			(stroke
				(width 0.05)
				(type solid)
			)
			(fill no)
			(layer "F.CrtYd")
		)
		(fp_line
			(start -0.803 0.406)
			(end -0.803 -0.408)
			(stroke
				(width 0.15)
				(type solid)
			)
			(layer "F.Fab")
		)
		(fp_line
			(start 0.8 -0.408)
			(end -0.803 -0.408)
			(stroke
				(width 0.15)
				(type solid)
			)
			(layer "F.Fab")
		)
		(fp_line
			(start 0.8 -0.408)
			(end 0.8 0.406)
			(stroke
				(width 0.15)
				(type solid)
			)
			(layer "F.Fab")
		)
		(fp_line
			(start 0.8 0.406)
			(end -0.803 0.406)
			(stroke
				(width 0.15)
				(type solid)
			)
			(layer "F.Fab")
		)
		(pad "1" smd roundrect
			(at -0.891 0)
			(size 0.762 1.09)
			(layers "F.Cu" "F.Mask" "F.Paste")
			(roundrect_rratio 0.15)
			(net 201 "+5V")
			(pintype "passive")
		)
		(pad "2" smd roundrect
			(at 0.888 0)
			(size 0.762 1.09)
			(layers "F.Cu" "F.Mask" "F.Paste")
			(roundrect_rratio 0.15)
			(net 34 "/HDMI + SD Card/HDMI_5V")
			(pintype "passive")
		)
	)
	(footprint "antmicro-footprints:R_0402_1005Metric"
		(layer "F.Cu")
		(at 185 183.115 -90)
		(descr "Resistor SMD 0402")
		(tags "resistor SMD 0402")
		(property "Reference" "R173"
			(at -1.122484 -0.772697 270)
			(layer "F.SilkS")
			(hide yes)
			(effects
				(font
					(size 0.7 0.7)
					(thickness 0.15)
				)
				(justify left bottom)
			)
		)
		(property "Value" "R_10k_0402"
			(at -1.011843 1.772047 270)
			(layer "F.Fab")
			(effects
				(font
					(size 0.7 0.7)
					(thickness 0.15)
				)
				(justify left bottom)
			)
		)
		(property "Datasheet" "https://www.bourns.com/docs/product-datasheets/cr.pdf"
			(at 0 0 270)
			(layer "F.Fab")
			(hide yes)
			(effects
				(font
					(size 1.27 1.27)
					(thickness 0.15)
				)
			)
		)
		(property "Author" "Antmicro"
			(at 1.885 368.115 0)
			(layer "F.Fab")
			(hide yes)
			(effects
				(font
					(size 1 1)
					(thickness 0.15)
				)
			)
		)
		(property "License" "Apache-2.0"
			(at 1.885 368.115 0)
			(layer "F.Fab")
			(hide yes)
			(effects
				(font
					(size 1 1)
					(thickness 0.15)
				)
			)
		)
		(property "MPN" "CR0402-FX-1002GLF"
			(at 1.885 368.115 0)
			(layer "F.Fab")
			(hide yes)
			(effects
				(font
					(size 1 1)
					(thickness 0.15)
				)
			)
		)
		(property "Manufacturer" "Bourns"
			(at 1.885 368.115 0)
			(layer "F.Fab")
			(hide yes)
			(effects
				(font
					(size 1 1)
					(thickness 0.15)
				)
			)
		)
		(property "Tolerance" "1%"
			(at 1.885 368.115 0)
			(layer "F.Fab")
			(hide yes)
			(effects
				(font
					(size 1 1)
					(thickness 0.15)
				)
			)
		)
		(property "Val" "10k"
			(at 1.885 368.115 0)
			(layer "F.Fab")
			(hide yes)
			(effects
				(font
					(size 1 1)
					(thickness 0.15)
				)
			)
		)
		(sheetname "/Supply/")
		(sheetfile "supply.kicad_sch")
		(attr smd)
		(fp_rect
			(start -0.93 -0.47)
			(end 0.93 0.47)
			(stroke
				(width 0.05)
				(type solid)
			)
			(fill no)
			(layer "F.CrtYd")
		)
		(fp_rect
			(start -0.5 -0.25)
			(end 0.5 0.25)
			(stroke
				(width 0.15)
				(type solid)
			)
			(fill no)
			(layer "F.Fab")
		)
		(pad "1" smd roundrect
			(at -0.485 0 270)
			(size 0.59 0.64)
			(layers "F.Cu" "F.Mask" "F.Paste")
			(roundrect_rratio 0.25)
			(net 200 "+3V3")
			(pintype "passive")
		)
		(pad "2" smd roundrect
			(at 0.485 0 270)
			(size 0.59 0.64)
			(layers "F.Cu" "F.Mask" "F.Paste")
			(roundrect_rratio 0.25)
			(net 385 "Net-(U25-~{PWRDN})")
			(pintype "passive")
		)
	)
	(footprint "antmicro-footprints:NetTie-2_SMD_Pad0.127mm"
		(layer "F.Cu")
		(at 189.4805 162.002)
		(descr "Net tie, 2 pin, 0.127mm  SMD pads")
		(tags "net tie")
		(property "Reference" "NT6"
			(at -0.128 -1.345 0)
			(layer "F.SilkS")
			(hide yes)
			(effects
				(font
					(size 0.7 0.7)
					(thickness 0.15)
				)
				(justify left bottom)
			)
		)
		(property "Value" "Net-Tie_P0.127mm"
			(at 0 1.199 0)
			(layer "F.Fab")
			(effects
				(font
					(size 0.7 0.7)
					(thickness 0.15)
				)
				(justify left bottom)
			)
		)
		(property "Author" "Antmicro"
			(at 0 0 0)
			(layer "F.Fab")
			(hide yes)
			(effects
				(font
					(size 1 1)
					(thickness 0.15)
				)
			)
		)
		(property "License" "Apache-2.0"
			(at 0 0 0)
			(layer "F.Fab")
			(hide yes)
			(effects
				(font
					(size 1 1)
					(thickness 0.15)
				)
			)
		)
		(property "MPN" ""
			(at 0 0 0)
			(layer "F.Fab")
			(hide yes)
			(effects
				(font
					(size 1 1)
					(thickness 0.15)
				)
			)
		)
		(property "Manufacturer" ""
			(at 0 0 0)
			(layer "F.Fab")
			(hide yes)
			(effects
				(font
					(size 1 1)
					(thickness 0.15)
				)
			)
		)
		(property ki_fp_filters "Net*Tie*")
		(sheetname "/Supply/")
		(sheetfile "supply.kicad_sch")
		(attr smd exclude_from_pos_files exclude_from_bom)
		(net_tie_pad_groups "1, 2")
		(fp_poly
			(pts
				(xy -0.0635 -0.0635) (xy 0.0625 -0.0635) (xy 0.0625 0.0635) (xy -0.0635 0.0635)
			)
			(stroke
				(width 0)
				(type solid)
			)
			(fill yes)
			(layer "F.Cu")
		)
		(pad "1" smd roundrect
			(at -0.127 0 180)
			(size 0.127 0.127)
			(layers "F.Cu")
			(roundrect_rratio 0.5)
			(chamfer_ratio 0)
			(chamfer top_left bottom_left)
			(net 141 "/Supply/5V_SEN_+")
			(pinfunction "1")
			(pintype "passive")
		)
		(pad "2" smd roundrect
			(at 0.126 0)
			(size 0.127 0.127)
			(layers "F.Cu")
			(roundrect_rratio 0.5)
			(chamfer_ratio 0)
			(chamfer top_left bottom_left)
			(net 60 "/Supply/5V_local")
			(pinfunction "2")
			(pintype "passive")
		)
	)
	(footprint "antmicro-footprints:R_0402_1005Metric"
		(layer "F.Cu")
		(at 97.75 136.06 -90)
		(descr "Resistor SMD 0402")
		(tags "resistor SMD 0402")
		(property "Reference" "R128"
			(at -1.122484 -0.772697 270)
			(layer "F.SilkS")
			(hide yes)
			(effects
				(font
					(size 0.7 0.7)
					(thickness 0.15)
				)
				(justify left bottom)
			)
		)
		(property "Value" "R_10k_0402"
			(at -1.011843 1.772047 270)
			(layer "F.Fab")
			(effects
				(font
					(size 0.7 0.7)
					(thickness 0.15)
				)
				(justify left bottom)
			)
		)
		(property "Datasheet" "https://www.bourns.com/docs/product-datasheets/cr.pdf"
			(at 0 0 270)
			(layer "F.Fab")
			(hide yes)
			(effects
				(font
					(size 1.27 1.27)
					(thickness 0.15)
				)
			)
		)
		(property "Author" "Antmicro"
			(at -38.31 233.81 0)
			(layer "F.Fab")
			(hide yes)
			(effects
				(font
					(size 1 1)
					(thickness 0.15)
				)
			)
		)
		(property "License" "Apache-2.0"
			(at -38.31 233.81 0)
			(layer "F.Fab")
			(hide yes)
			(effects
				(font
					(size 1 1)
					(thickness 0.15)
				)
			)
		)
		(property "MPN" "CR0402-FX-1002GLF"
			(at -38.31 233.81 0)
			(layer "F.Fab")
			(hide yes)
			(effects
				(font
					(size 1 1)
					(thickness 0.15)
				)
			)
		)
		(property "Manufacturer" "Bourns"
			(at -38.31 233.81 0)
			(layer "F.Fab")
			(hide yes)
			(effects
				(font
					(size 1 1)
					(thickness 0.15)
				)
			)
		)
		(property "Tolerance" "1%"
			(at -38.31 233.81 0)
			(layer "F.Fab")
			(hide yes)
			(effects
				(font
					(size 1 1)
					(thickness 0.15)
				)
			)
		)
		(property "Val" "10k"
			(at -38.31 233.81 0)
			(layer "F.Fab")
			(hide yes)
			(effects
				(font
					(size 1 1)
					(thickness 0.15)
				)
			)
		)
		(sheetname "/DDR5 SODIMM/")
		(sheetfile "ddr5-sodimm.kicad_sch")
		(attr smd)
		(fp_rect
			(start -0.93 -0.47)
			(end 0.93 0.47)
			(stroke
				(width 0.05)
				(type solid)
			)
			(fill no)
			(layer "F.CrtYd")
		)
		(fp_rect
			(start -0.5 -0.25)
			(end 0.5 0.25)
			(stroke
				(width 0.15)
				(type solid)
			)
			(fill no)
			(layer "F.Fab")
		)
		(pad "1" smd roundrect
			(at -0.485 0 270)
			(size 0.59 0.64)
			(layers "F.Cu" "F.Mask" "F.Paste")
			(roundrect_rratio 0.25)
			(net 1 "GND")
			(pintype "passive")
		)
		(pad "2" smd roundrect
			(at 0.485 0 270)
			(size 0.59 0.64)
			(layers "F.Cu" "F.Mask" "F.Paste")
			(roundrect_rratio 0.25)
			(net 49 "/DDR5 SODIMM/HSA")
			(pintype "passive")
		)
	)
	(footprint "antmicro-footprints:SOD-523"
		(layer "F.Cu")
		(at 177.449 189.35 180)
		(property "Reference" "D17"
			(at -1.051 2.7 0)
			(layer "F.SilkS")
			(effects
				(font
					(size 0.7 0.7)
					(thickness 0.15)
				)
				(justify right top)
			)
		)
		(property "Value" "BAT54-02V-G3-08"
			(at 0 1.499 0)
			(layer "F.Fab")
			(effects
				(font
					(size 0.7 0.7)
					(thickness 0.15)
				)
				(justify right top)
			)
		)
		(property "Datasheet" "https://www.vishay.com/docs/85633/bat5402v.pdf"
			(at 0 0 0)
			(layer "F.Fab")
			(hide yes)
			(effects
				(font
					(size 1.27 1.27)
					(thickness 0.15)
				)
			)
		)
		(property "Description" "Small Signal Schottky Diode, Single, 30 V, 200 mA, 800 mV, 600 mA, 125 °C"
			(at 0 0 0)
			(layer "F.Fab")
			(hide yes)
			(effects
				(font
					(size 1.27 1.27)
					(thickness 0.15)
				)
			)
		)
		(property "MPN" "BAT54-02V-G3-08"
			(at 0 0 180)
			(unlocked yes)
			(layer "F.Fab")
			(hide yes)
			(effects
				(font
					(size 1 1)
					(thickness 0.15)
				)
			)
		)
		(property "Manufacturer" "Vishay"
			(at 0 0 180)
			(unlocked yes)
			(layer "F.Fab")
			(hide yes)
			(effects
				(font
					(size 1 1)
					(thickness 0.15)
				)
			)
		)
		(property "Author" "Antmicro"
			(at 0 0 180)
			(unlocked yes)
			(layer "F.Fab")
			(hide yes)
			(effects
				(font
					(size 1 1)
					(thickness 0.15)
				)
			)
		)
		(property "License" "Apache-2.0"
			(at 0 0 180)
			(unlocked yes)
			(layer "F.Fab")
			(hide yes)
			(effects
				(font
					(size 1 1)
					(thickness 0.15)
				)
			)
		)
		(sheetname "/I^{2}C/")
		(sheetfile "i2c.kicad_sch")
		(attr smd)
		(fp_line
			(start -0.35 -0.5)
			(end -0.35 0.5)
			(stroke
				(width 0.15)
				(type solid)
			)
			(layer "F.SilkS")
		)
		(fp_poly
			(pts
				(xy -1 -0.6) (xy 1 -0.6) (xy 1 0.6) (xy -1 0.6)
			)
			(stroke
				(width 0.05)
				(type solid)
			)
			(fill no)
			(layer "F.CrtYd")
		)
		(fp_line
			(start 0.65 -0.425)
			(end 0.65 0.423)
			(stroke
				(width 0.15)
				(type solid)
			)
			(layer "F.Fab")
		)
		(fp_line
			(start -0.35 -0.4)
			(end -0.35 0.4)
			(stroke
				(width 0.15)
				(type solid)
			)
			(layer "F.Fab")
		)
		(fp_line
			(start -0.652 0.423)
			(end 0.65 0.423)
			(stroke
				(width 0.15)
				(type solid)
			)
			(layer "F.Fab")
		)
		(fp_line
			(start -0.652 0.423)
			(end -0.652 -0.425)
			(stroke
				(width 0.15)
				(type solid)
			)
			(layer "F.Fab")
		)
		(fp_line
			(start -0.652 -0.425)
			(end 0.65 -0.425)
			(stroke
				(width 0.15)
				(type solid)
			)
			(layer "F.Fab")
		)
		(fp_text user "License: Apache-2.0"
			(at -1.276 5.9 0)
			(layer "F.Fab")
			(effects
				(font
					(size 0.7 0.7)
					(thickness 0.15)
				)
				(justify right top)
			)
		)
		(fp_text user "${REFERENCE}"
			(at -1.276 3.499 0)
			(layer "F.Fab")
			(effects
				(font
					(size 0.7 0.7)
					(thickness 0.15)
				)
				(justify right top)
			)
		)
		(fp_text user "Author: Antmicro"
			(at -1.276 4.7 0)
			(layer "F.Fab")
			(effects
				(font
					(size 0.7 0.7)
					(thickness 0.15)
				)
				(justify right top)
			)
		)
		(pad "1" smd roundrect
			(at -0.701 0 180)
			(size 0.5 0.6)
			(layers "F.Cu" "F.Mask" "F.Paste")
			(roundrect_rratio 0.25)
			(net 759 "Net-(D17-C)")
			(pinfunction "C")
			(pintype "passive")
		)
		(pad "2" smd roundrect
			(at 0.699001 0 180)
			(size 0.5 0.6)
			(layers "F.Cu" "F.Mask" "F.Paste")
			(roundrect_rratio 0.25)
			(net 200 "+3V3")
			(pinfunction "A")
			(pintype "passive")
		)
	)
	(footprint "antmicro-footprints:TP_SMD_1mm"
		(layer "F.Cu")
		(at 186.4 184.85)
		(property "Reference" "TP8"
			(at 0 -0.731898 0)
			(layer "F.SilkS")
			(hide yes)
			(effects
				(font
					(size 0.7 0.7)
					(thickness 0.15)
				)
				(justify left bottom)
			)
		)
		(property "Value" "TP_1mm_SMD"
			(at 0 1.4 0)
			(layer "F.Fab")
			(effects
				(font
					(size 0.7 0.7)
					(thickness 0.15)
				)
				(justify left bottom)
			)
		)
		(property "Author" "Antmicro"
			(at 0 0 0)
			(layer "F.Fab")
			(hide yes)
			(effects
				(font
					(size 1 1)
					(thickness 0.15)
				)
			)
		)
		(property "License" "Apache-2.0"
			(at 0 0 0)
			(layer "F.Fab")
			(hide yes)
			(effects
				(font
					(size 1 1)
					(thickness 0.15)
				)
			)
		)
		(property "MPN" ""
			(at 0 0 0)
			(layer "F.Fab")
			(hide yes)
			(effects
				(font
					(size 1 1)
					(thickness 0.15)
				)
			)
		)
		(property "Manufacturer" ""
			(at 0 0 0)
			(layer "F.Fab")
			(hide yes)
			(effects
				(font
					(size 1 1)
					(thickness 0.15)
				)
			)
		)
		(sheetname "/Supply/")
		(sheetfile "supply.kicad_sch")
		(attr exclude_from_pos_files)
		(pad "1" smd circle
			(at 0 0)
			(size 1 1)
			(layers "F.Cu" "F.Mask")
			(net 187 "+1V0_MGTAVCC")
			(pinfunction "1")
			(pintype "passive")
		)
	)
	(footprint "antmicro-footprints:R_0402_1005Metric"
		(layer "F.Cu")
		(at 121.799499 186.6 -90)
		(descr "Resistor SMD 0402")
		(tags "resistor SMD 0402")
		(property "Reference" "R7"
			(at -1.122484 -0.772697 270)
			(layer "F.SilkS")
			(hide yes)
			(effects
				(font
					(size 0.7 0.7)
					(thickness 0.15)
				)
				(justify left bottom)
			)
		)
		(property "Value" "R_22R_0402"
			(at -1.011843 1.772047 270)
			(layer "F.Fab")
			(effects
				(font
					(size 0.7 0.7)
					(thickness 0.15)
				)
				(justify left bottom)
			)
		)
		(property "Datasheet" "https://www.bourns.com/docs/product-datasheets/cr.pdf"
			(at 0 0 270)
			(layer "F.Fab")
			(hide yes)
			(effects
				(font
					(size 1.27 1.27)
					(thickness 0.15)
				)
			)
		)
		(property "Author" "Antmicro"
			(at -64.800501 308.399499 0)
			(layer "F.Fab")
			(hide yes)
			(effects
				(font
					(size 1 1)
					(thickness 0.15)
				)
			)
		)
		(property "License" "Apache-2.0"
			(at -64.800501 308.399499 0)
			(layer "F.Fab")
			(hide yes)
			(effects
				(font
					(size 1 1)
					(thickness 0.15)
				)
			)
		)
		(property "MPN" "CR0402-FX-22R0GLF"
			(at -64.800501 308.399499 0)
			(layer "F.Fab")
			(hide yes)
			(effects
				(font
					(size 1 1)
					(thickness 0.15)
				)
			)
		)
		(property "Manufacturer" "Bourns"
			(at -64.800501 308.399499 0)
			(layer "F.Fab")
			(hide yes)
			(effects
				(font
					(size 1 1)
					(thickness 0.15)
				)
			)
		)
		(property "Tolerance" "1%"
			(at -64.800501 308.399499 0)
			(layer "F.Fab")
			(hide yes)
			(effects
				(font
					(size 1 1)
					(thickness 0.15)
				)
			)
		)
		(property "Val" "22R"
			(at -64.800501 308.399499 0)
			(layer "F.Fab")
			(hide yes)
			(effects
				(font
					(size 1 1)
					(thickness 0.15)
				)
			)
		)
		(sheetname "/HyperRAM + QSPI Flash/")
		(sheetfile "hyperram-flash.kicad_sch")
		(attr smd)
		(fp_rect
			(start -0.93 -0.47)
			(end 0.93 0.47)
			(stroke
				(width 0.05)
				(type solid)
			)
			(fill no)
			(layer "F.CrtYd")
		)
		(fp_rect
			(start -0.5 -0.25)
			(end 0.5 0.25)
			(stroke
				(width 0.15)
				(type solid)
			)
			(fill no)
			(layer "F.Fab")
		)
		(pad "1" smd roundrect
			(at -0.485 0 270)
			(size 0.59 0.64)
			(layers "F.Cu" "F.Mask" "F.Paste")
			(roundrect_rratio 0.25)
			(net 363 "/HyperRAM + QSPI Flash/IO1")
			(pintype "passive")
		)
		(pad "2" smd roundrect
			(at 0.485 0 270)
			(size 0.59 0.64)
			(layers "F.Cu" "F.Mask" "F.Paste")
			(roundrect_rratio 0.25)
			(net 627 "/FPGA Config/FLASH.IO1")
			(pintype "passive")
		)
	)
)
